# T6G (Grand Teton) — schematic netlist excerpt (pin names and nets, part order shuffled) for the footprints in the layout excerpt that follows; sources: Cadence DE-HDL packaged netlist, KiCad conversion of 04192023_DAF0TMB3IC0_F0TG_MB_C_brd_V02_OCP.brd

R972  Q_RES  4.7K 5% EMPTY  pkg 0201LF  page 276 : A = P1V8_CPU0_RT_1D ; B = RT_CPU0_P0_SCAN_MODE
C271  Q_CAP  22UF 4V 20% X6S  pkg C0402  page 69 : A = PVDDCR_CPU0_P0 ; B = GND
R110  Q_RES  1K 1% EMPTY  pkg 0402LF  page 104 : A = P3V3 ; B = PWRGD_CHG_CPU1_DIMM0

(kicad_pcb
	(version 20260206)
	(generator "pcbnew")
	(generator_version "10.0")
	(general
		(thickness 1.6)
		(legacy_teardrops no)
	)
	(paper "A4")
	(title_block
		(title "04192023_DAF0TMB3IC0_F0TG_MB_C_brd_V02_OCP.brd")
		(comment 1 "Grand Teton / footprints 7656-7658 of 8354")
	)
	(layers
		(0 "F.Cu" signal "TOP")
		(4 "In1.Cu" signal "GND")
		(6 "In2.Cu" signal "IN1")
		(8 "In3.Cu" signal "GND1")
		(10 "In4.Cu" signal "IN2")
		(12 "In5.Cu" signal "GND2")
		(14 "In6.Cu" signal "IN3")
		(16 "In7.Cu" signal "GND3")
		(18 "In8.Cu" signal "VCC")
		(20 "In9.Cu" signal "VCC1")
		(22 "In10.Cu" signal "GND4")
		(24 "In11.Cu" signal "IN4")
		(26 "In12.Cu" signal "GND5")
		(28 "In13.Cu" signal "IN5")
		(30 "In14.Cu" signal "GND6")
		(32 "In15.Cu" signal "IN6")
		(34 "In16.Cu" signal "GND7")
		(2 "B.Cu" signal "BOTTOM")
		(9 "F.Adhes" user "F.Adhesive")
		(11 "B.Adhes" user "B.Adhesive")
		(13 "F.Paste" user "Package Geometry/Pastemask Top")
		(15 "B.Paste" user "Package Geometry/Pastemask Bottom")
		(5 "F.SilkS" user "Ref Des/Silkscreen Top")
		(7 "B.SilkS" user "Ref Des/Silkscreen Bottom")
		(1 "F.Mask" user "Board Geometry/Soldermask Top")
		(3 "B.Mask" user "Board Geometry/Soldermask Bottom")
		(17 "Dwgs.User" user "User.Drawings")
		(19 "Cmts.User" user "User.Comments")
		(21 "Eco1.User" user "User.Eco1")
		(23 "Eco2.User" user "User.Eco2")
		(25 "Edge.Cuts" user "Board Geometry/Outline")
		(27 "Margin" user)
		(31 "F.CrtYd" user "Package Geometry/Place Bound Top")
		(29 "B.CrtYd" user "Package Geometry/Place Bound Bottom")
		(35 "F.Fab" user "Ref Des/Assembly Top")
		(33 "B.Fab" user "Ref Des/Assembly Bottom")
	)
	(footprint ""
		(layer "B.Cu")
		(at 367.741454 -250.89231)
		(property "Reference" "C271"
			(at 0 0 0)
			(layer "B.SilkS")
			(hide yes)
			(effects
				(font
					(size 1.27 1.27)
				)
				(justify mirror)
			)
		)
		(property "Value" ""
			(at 0 0 0)
			(layer "B.Fab")
			(effects
				(font
					(size 1.27 1.27)
				)
				(justify mirror)
			)
		)
		(duplicate_pad_numbers_are_jumpers no)
		(fp_line
			(start -0.7874 -0.4064)
			(end -0.7874 0.4064)
			(stroke
				(width 0.1524)
				(type default)
			)
			(layer "B.SilkS")
		)
		(fp_line
			(start -0.7874 0.4064)
			(end 0.7874 0.4064)
			(stroke
				(width 0.1524)
				(type default)
			)
			(layer "B.SilkS")
		)
		(fp_line
			(start 0.7874 -0.4064)
			(end -0.7874 -0.4064)
			(stroke
				(width 0.1524)
				(type default)
			)
			(layer "B.SilkS")
		)
		(fp_line
			(start 0.7874 0.4064)
			(end 0.7874 -0.4064)
			(stroke
				(width 0.1524)
				(type default)
			)
			(layer "B.SilkS")
		)
		(fp_line
			(start -0.67945 -0.3048)
			(end -0.67945 0.3048)
			(stroke
				(width 0.1)
				(type default)
			)
			(layer "B.Fab")
		)
		(fp_line
			(start -0.67945 0.3048)
			(end -0.120396 0.3048)
			(stroke
				(width 0.1)
				(type default)
			)
			(layer "B.Fab")
		)
		(fp_line
			(start -0.12065 -0.3048)
			(end -0.67945 -0.3048)
			(stroke
				(width 0.1)
				(type default)
			)
			(layer "B.Fab")
		)
		(fp_line
			(start -0.12065 -0.2794)
			(end -0.12065 -0.3048)
			(stroke
				(width 0.1)
				(type default)
			)
			(layer "B.Fab")
		)
		(fp_line
			(start -0.120396 0.2794)
			(end 0.12065 0.2794)
			(stroke
				(width 0.1)
				(type default)
			)
			(layer "B.Fab")
		)
		(fp_line
			(start -0.120396 0.3048)
			(end -0.120396 0.2794)
			(stroke
				(width 0.1)
				(type default)
			)
			(layer "B.Fab")
		)
		(fp_line
			(start 0.12065 -0.305054)
			(end 0.12065 -0.2794)
			(stroke
				(width 0.1)
				(type default)
			)
			(layer "B.Fab")
		)
		(fp_line
			(start 0.12065 -0.2794)
			(end -0.12065 -0.2794)
			(stroke
				(width 0.1)
				(type default)
			)
			(layer "B.Fab")
		)
		(fp_line
			(start 0.12065 0.2794)
			(end 0.12065 0.3048)
			(stroke
				(width 0.1)
				(type default)
			)
			(layer "B.Fab")
		)
		(fp_line
			(start 0.12065 0.3048)
			(end 0.67945 0.3048)
			(stroke
				(width 0.1)
				(type default)
			)
			(layer "B.Fab")
		)
		(fp_line
			(start 0.67945 -0.305054)
			(end 0.12065 -0.305054)
			(stroke
				(width 0.1)
				(type default)
			)
			(layer "B.Fab")
		)
		(fp_line
			(start 0.67945 0.3048)
			(end 0.67945 -0.305054)
			(stroke
				(width 0.1)
				(type default)
			)
			(layer "B.Fab")
		)
		(pad "1" smd circle
			(at 0.40005 0 180)
			(size 0 0)
			(layers "B.Cu" "B.Mask" "B.Paste")
			(net "PVDDCR_CPU0_P0")
		)
		(pad "2" smd circle
			(at -0.40005 0 180)
			(size 0 0)
			(layers "B.Cu" "B.Mask" "B.Paste")
			(net "GND")
		)
	)
	(footprint ""
		(layer "B.Cu")
		(at 299.265594 -391.06856 180)
		(property "Reference" "R972"
			(at 0 0 0)
			(layer "B.SilkS")
			(hide yes)
			(effects
				(font
					(size 1.27 1.27)
				)
				(justify mirror)
			)
		)
		(property "Value" ""
			(at 0 0 0)
			(layer "B.Fab")
			(effects
				(font
					(size 1.27 1.27)
				)
				(justify mirror)
			)
		)
		(duplicate_pad_numbers_are_jumpers no)
		(fp_line
			(start 0.32512 0.175006)
			(end 0.32512 -0.175006)
			(stroke
				(width 0.1)
				(type default)
			)
			(layer "B.Fab")
		)
		(fp_line
			(start 0.32512 -0.175006)
			(end -0.32512 -0.175006)
			(stroke
				(width 0.1)
				(type default)
			)
			(layer "B.Fab")
		)
		(fp_line
			(start -0.32512 0.175006)
			(end 0.32512 0.175006)
			(stroke
				(width 0.1)
				(type default)
			)
			(layer "B.Fab")
		)
		(fp_line
			(start -0.32512 -0.175006)
			(end -0.32512 0.175006)
			(stroke
				(width 0.1)
				(type default)
			)
			(layer "B.Fab")
		)
		(pad "1" smd rect
			(at 0.2667 0)
			(size 0.3048 0.381)
			(layers "B.Cu" "B.Mask" "B.Paste")
			(net "P1V8_CPU0_RT_1D")
		)
		(pad "2" smd rect
			(at -0.2667 0 180)
			(size 0.3048 0.381)
			(layers "B.Cu" "B.Mask" "B.Paste")
			(net "RT_CPU0_P0_SCAN_MODE")
		)
	)
	(footprint ""
		(layer "B.Cu")
		(at 165.18382 -193.996564)
		(property "Reference" "R110"
			(at 0 0 0)
			(layer "B.SilkS")
			(hide yes)
			(effects
				(font
					(size 1.27 1.27)
				)
				(justify mirror)
			)
		)
		(property "Value" ""
			(at 0 0 0)
			(layer "B.Fab")
			(effects
				(font
					(size 1.27 1.27)
				)
				(justify mirror)
			)
		)
		(duplicate_pad_numbers_are_jumpers no)
		(fp_line
			(start -0.7874 -0.4064)
			(end -0.7874 0.4064)
			(stroke
				(width 0.1524)
				(type default)
			)
			(layer "B.SilkS")
		)
		(fp_line
			(start -0.7874 0.4064)
			(end 0.7874 0.4064)
			(stroke
				(width 0.1524)
				(type default)
			)
			(layer "B.SilkS")
		)
		(fp_line
			(start 0.7874 -0.4064)
			(end -0.7874 -0.4064)
			(stroke
				(width 0.1524)
				(type default)
			)
			(layer "B.SilkS")
		)
		(fp_line
			(start 0.7874 0.4064)
			(end 0.7874 -0.4064)
			(stroke
				(width 0.1524)
				(type default)
			)
			(layer "B.SilkS")
		)
		(fp_line
			(start -0.67945 -0.3048)
			(end -0.67945 0.3048)
			(stroke
				(width 0.1)
				(type default)
			)
			(layer "B.Fab")
		)
		(fp_line
			(start -0.67945 0.3048)
			(end -0.120396 0.3048)
			(stroke
				(width 0.1)
				(type default)
			)
			(layer "B.Fab")
		)
		(fp_line
			(start -0.12065 -0.3048)
			(end -0.67945 -0.3048)
			(stroke
				(width 0.1)
				(type default)
			)
			(layer "B.Fab")
		)
		(fp_line
			(start -0.12065 -0.2794)
			(end -0.12065 -0.3048)
			(stroke
				(width 0.1)
				(type default)
			)
			(layer "B.Fab")
		)
		(fp_line
			(start -0.120396 0.2794)
			(end 0.12065 0.2794)
			(stroke
				(width 0.1)
				(type default)
			)
			(layer "B.Fab")
		)
		(fp_line
			(start -0.120396 0.3048)
			(end -0.120396 0.2794)
			(stroke
				(width 0.1)
				(type default)
			)
			(layer "B.Fab")
		)
		(fp_line
			(start 0.12065 -0.305054)
			(end 0.12065 -0.2794)
			(stroke
				(width 0.1)
				(type default)
			)
			(layer "B.Fab")
		)
		(fp_line
			(start 0.12065 -0.2794)
			(end -0.12065 -0.2794)
			(stroke
				(width 0.1)
				(type default)
			)
			(layer "B.Fab")
		)
		(fp_line
			(start 0.12065 0.2794)
			(end 0.12065 0.3048)
			(stroke
				(width 0.1)
				(type default)
			)
			(layer "B.Fab")
		)
		(fp_line
			(start 0.12065 0.3048)
			(end 0.67945 0.3048)
			(stroke
				(width 0.1)
				(type default)
			)
			(layer "B.Fab")
		)
		(fp_line
			(start 0.67945 -0.305054)
			(end 0.12065 -0.305054)
			(stroke
				(width 0.1)
				(type default)
			)
			(layer "B.Fab")
		)
		(fp_line
			(start 0.67945 0.3048)
			(end 0.67945 -0.305054)
			(stroke
				(width 0.1)
				(type default)
			)
			(layer "B.Fab")
		)
		(pad "1" smd circle
			(at 0.40005 0 180)
			(size 0 0)
			(layers "B.Cu" "B.Mask" "B.Paste")
			(net "P3V3")
		)
		(pad "2" smd circle
			(at -0.40005 0 180)
			(size 0 0)
			(layers "B.Cu" "B.Mask" "B.Paste")
			(net "PWRGD_CHG_CPU1_DIMM0")
		)
	)
)
